(kicad_pcb
	(version 20260206)
	(generator "pcbnew")
	(generator_version "10.0")
	(general
		(thickness 1.6)
		(legacy_teardrops no)
	)
	(paper "A4")
	(title_block
		(title "Wiwynn_Tioga_Pass_MB.brd")
		(comment 1 "Tioga Pass / footprints 1577-1583 of 4770")
	)
	(layers
		(0 "F.Cu" signal "TOP")
		(4 "In1.Cu" signal "L2GND")
		(6 "In2.Cu" signal "L3")
		(8 "In3.Cu" signal "L4GND")
		(10 "In4.Cu" signal "L5")
		(12 "In5.Cu" signal "L6GND")
		(14 "In6.Cu" signal "L7VCC")
		(16 "In7.Cu" signal "L8VCC")
		(18 "In8.Cu" signal "L9GND")
		(20 "In9.Cu" signal "L10")
		(22 "In10.Cu" signal "L11GND")
		(24 "In11.Cu" signal "L12")
		(26 "In12.Cu" signal "L13GND")
		(2 "B.Cu" signal "BOTTOM")
		(9 "F.Adhes" user "F.Adhesive")
		(11 "B.Adhes" user "B.Adhesive")
		(13 "F.Paste" user "Package Geometry/Pastemask Top")
		(15 "B.Paste" user "Package Geometry/Pastemask Bottom")
		(5 "F.SilkS" user "Ref Des/Silkscreen Top")
		(7 "B.SilkS" user "Ref Des/Silkscreen Bottom")
		(1 "F.Mask" user "Board Geometry/Soldermask Top")
		(3 "B.Mask" user "Board Geometry/Soldermask Bottom")
		(17 "Dwgs.User" user "User.Drawings")
		(19 "Cmts.User" user "User.Comments")
		(21 "Eco1.User" user "User.Eco1")
		(23 "Eco2.User" user "User.Eco2")
		(25 "Edge.Cuts" user "Board Geometry/Outline")
		(27 "Margin" user)
		(31 "F.CrtYd" user "Package Geometry/Place Bound Top")
		(29 "B.CrtYd" user "Package Geometry/Place Bound Bottom")
		(35 "F.Fab" user "Ref Des/Assembly Top")
		(33 "B.Fab" user "Ref Des/Assembly Bottom")
	)
	(footprint ""
		(layer "F.Cu")
		(at 1.148588 -14.695932)
		(property "Reference" "CT31"
			(at -0.81153 0.6096 90)
			(unlocked yes)
			(layer "F.SilkS")
			(effects
				(font
					(size 0.7874 0.5842)
					(thickness 0.1524)
				)
				(justify left)
			)
		)
		(property "Value" ""
			(at 0 0 0)
			(layer "F.Fab")
			(effects
				(font
					(size 1.27 1.27)
				)
			)
		)
		(duplicate_pad_numbers_are_jumpers no)
		(fp_rect
			(start -0.3048 0.9906)
			(end 0.3048 -0.1016)
			(stroke
				(width 0)
				(type default)
			)
			(fill no)
			(layer "F.CrtYd")
		)
		(fp_line
			(start -0.3048 -0.1016)
			(end -0.3048 0.9906)
			(stroke
				(width 0.1)
				(type default)
			)
			(layer "F.Fab")
		)
		(fp_line
			(start -0.3048 0.9906)
			(end 0.3048 0.9906)
			(stroke
				(width 0.1)
				(type default)
			)
			(layer "F.Fab")
		)
		(fp_line
			(start 0.3048 -0.1016)
			(end -0.3048 -0.1016)
			(stroke
				(width 0.1)
				(type default)
			)
			(layer "F.Fab")
		)
		(fp_line
			(start 0.3048 0.9906)
			(end 0.3048 -0.1016)
			(stroke
				(width 0.1)
				(type default)
			)
			(layer "F.Fab")
		)
		(pad "1" smd rect
			(at 0 0)
			(size 0.508 0.508)
			(layers "F.Cu" "F.Mask" "F.Paste")
			(net "VR_PVDDQ_GHJ_AIREF2")
		)
		(pad "2" smd rect
			(at 0 0.889)
			(size 0.508 0.508)
			(layers "F.Cu" "F.Mask" "F.Paste")
			(net "GND")
		)
		(zone
			(layer "F.Cu")
			(hatch none 0.5)
			(connect_pads
				(clearance 0)
			)
			(min_thickness 0.25)
			(keepout
				(tracks allowed)
				(vias not_allowed)
				(pads allowed)
				(copperpour not_allowed)
				(footprints allowed)
			)
			(placement
				(enabled no)
				(sheetname "")
			)
			(fill
				(thermal_gap 0.5)
				(thermal_bridge_width 0.5)
				(island_removal_mode 0)
			)
			(polygon
				(pts
					(xy 0.894588 -14.060932) (xy 1.402588 -14.060932) (xy 1.402588 -14.441932) (xy 0.894588 -14.441932)
				)
			)
		)
		(zone
			(layer "F.Cu")
			(hatch none 0.5)
			(connect_pads
				(clearance 0)
			)
			(min_thickness 0.25)
			(keepout
				(tracks not_allowed)
				(vias allowed)
				(pads allowed)
				(copperpour not_allowed)
				(footprints allowed)
			)
			(placement
				(enabled no)
				(sheetname "")
			)
			(fill
				(thermal_gap 0.5)
				(thermal_bridge_width 0.5)
				(island_removal_mode 0)
			)
			(polygon
				(pts
					(xy 0.894588 -14.060932) (xy 1.402588 -14.060932) (xy 1.402588 -14.441932) (xy 0.894588 -14.441932)
				)
			)
		)
	)
	(footprint ""
		(layer "F.Cu")
		(at 410.048964 -23.070566)
		(property "Reference" "R25W143"
			(at -0.8382 -0.67818 0)
			(unlocked yes)
			(layer "F.SilkS")
			(effects
				(font
					(size 0.4064 0.254)
					(thickness 0.1524)
				)
				(justify left)
			)
		)
		(property "Value" ""
			(at 0 0 0)
			(layer "F.Fab")
			(effects
				(font
					(size 1.27 1.27)
				)
			)
		)
		(duplicate_pad_numbers_are_jumpers no)
		(fp_poly
			(pts
				(xy -0.2794 -0.1016) (xy 0.2794 -0.1016) (xy 0.2794 0.9906) (xy -0.2794 0.9906)
			)
			(stroke
				(width 0)
				(type default)
			)
			(fill no)
			(layer "F.CrtYd")
		)
		(fp_line
			(start -0.2794 -0.1016)
			(end -0.2794 0.9906)
			(stroke
				(width 0.1)
				(type default)
			)
			(layer "F.Fab")
		)
		(fp_line
			(start -0.2794 0.9906)
			(end 0.2794 0.9906)
			(stroke
				(width 0.1)
				(type default)
			)
			(layer "F.Fab")
		)
		(fp_line
			(start 0.2794 -0.1016)
			(end -0.2794 -0.1016)
			(stroke
				(width 0.1)
				(type default)
			)
			(layer "F.Fab")
		)
		(fp_line
			(start 0.2794 0.9906)
			(end 0.2794 -0.1016)
			(stroke
				(width 0.1)
				(type default)
			)
			(layer "F.Fab")
		)
		(pad "1" smd rect
			(at 0 0)
			(size 0.508 0.508)
			(layers "F.Cu" "F.Mask" "F.Paste")
			(net "FM_GLOBAL_RST_WARN_N_R")
		)
		(pad "2" smd rect
			(at 0 0.889)
			(size 0.508 0.508)
			(layers "F.Cu" "F.Mask" "F.Paste")
			(net "FM_GLOBAL_RST_WARN_N")
		)
		(zone
			(layer "F.Cu")
			(hatch none 0.5)
			(connect_pads
				(clearance 0)
			)
			(min_thickness 0.25)
			(keepout
				(tracks allowed)
				(vias not_allowed)
				(pads allowed)
				(copperpour not_allowed)
				(footprints allowed)
			)
			(placement
				(enabled no)
				(sheetname "")
			)
			(fill
				(thermal_gap 0.5)
				(thermal_bridge_width 0.5)
				(island_removal_mode 0)
			)
			(polygon
				(pts
					(xy 409.794964 -22.816566) (xy 410.302964 -22.816566) (xy 410.302964 -22.435566) (xy 409.794964 -22.435566)
				)
			)
		)
		(zone
			(layer "F.Cu")
			(hatch none 0.5)
			(connect_pads
				(clearance 0)
			)
			(min_thickness 0.25)
			(keepout
				(tracks not_allowed)
				(vias allowed)
				(pads allowed)
				(copperpour not_allowed)
				(footprints allowed)
			)
			(placement
				(enabled no)
				(sheetname "")
			)
			(fill
				(thermal_gap 0.5)
				(thermal_bridge_width 0.5)
				(island_removal_mode 0)
			)
			(polygon
				(pts
					(xy 409.794964 -22.435566) (xy 410.302964 -22.435566) (xy 410.302964 -22.816566) (xy 409.794964 -22.816566)
				)
			)
		)
	)
	(footprint ""
		(layer "F.Cu")
		(at 19.177 10.7315 -90)
		(property "Reference" "T1P27"
			(at 0 0 270)
			(layer "F.SilkS")
			(hide yes)
			(effects
				(font
					(size 1.27 1.27)
				)
			)
		)
		(property "Value" "*"
			(at 0 -3.44805 270)
			(unlocked yes)
			(layer "F.Fab")
			(hide yes)
			(effects
				(font
					(size 0.889 0.889)
					(thickness 0.1524)
				)
			)
		)
		(property "Device Type" "TPAD-SE-2P-GP_DISCRET-GA1-TPADA"
			(at 0 -4.97205 270)
			(unlocked yes)
			(layer "F.Fab")
			(hide yes)
			(effects
				(font
					(size 0.889 0.889)
					(thickness 0.1524)
				)
			)
		)
		(duplicate_pad_numbers_are_jumpers no)
		(fp_line
			(start -1.016 2.286)
			(end -1.016 -2.286)
			(stroke
				(width 0.1524)
				(type default)
			)
			(layer "F.SilkS")
		)
		(fp_line
			(start 1.016 2.286)
			(end -1.016 2.286)
			(stroke
				(width 0.1524)
				(type default)
			)
			(layer "F.SilkS")
		)
		(fp_line
			(start -1.016 -2.286)
			(end 1.016 -2.286)
			(stroke
				(width 0.1524)
				(type default)
			)
			(layer "F.SilkS")
		)
		(fp_line
			(start 1.016 -2.286)
			(end 1.016 2.286)
			(stroke
				(width 0.1524)
				(type default)
			)
			(layer "F.SilkS")
		)
		(fp_rect
			(start -1.27 2.54)
			(end 1.27 -2.54)
			(stroke
				(width 0)
				(type default)
			)
			(fill no)
			(layer "F.CrtYd")
		)
		(fp_rect
			(start -1.27 2.54)
			(end 1.27 -2.54)
			(stroke
				(width 0)
				(type default)
			)
			(fill no)
			(layer "F.Fab")
		)
		(pad "1" thru_hole circle
			(at 0 -1.27 270)
			(size 1.524 1.524)
			(drill 0.9144)
			(layers "*.Cu" "*.Mask")
			(remove_unused_layers no)
			(net "L5_40OHM_6INCH")
			(clearance -0.0508)
			(thermal_gap 0.127)
			(padstack
				(mode front_inner_back)
				(layer "Inner"
					(shape circle)
					(size 1.1684 1.1684)
					(clearance 0.127)
				)
				(layer "B.Cu"
					(shape circle)
					(size 1.524 1.524)
					(clearance -0.0508)
				)
			)
		)
		(pad "GND1" thru_hole rect
			(at 0 1.27 270)
			(size 1.524 1.524)
			(drill 0.9144)
			(layers "*.Cu" "*.Mask")
			(remove_unused_layers no)
			(net "GND")
			(clearance -0.0508)
			(thermal_gap 0.127)
			(padstack
				(mode front_inner_back)
				(layer "Inner"
					(shape circle)
					(size 1.1684 1.1684)
					(clearance 0.127)
				)
				(layer "B.Cu"
					(shape rect)
					(size 1.524 1.524)
					(clearance -0.0508)
				)
			)
		)
	)
	(footprint ""
		(layer "F.Cu")
		(at 169.0497 -132.5372)
		(property "Reference" "R4B2"
			(at 0 0 0)
			(layer "F.SilkS")
			(hide yes)
			(effects
				(font
					(size 1.27 1.27)
				)
			)
		)
		(property "Value" ""
			(at 0 0 0)
			(layer "F.Fab")
			(effects
				(font
					(size 1.27 1.27)
				)
			)
		)
		(duplicate_pad_numbers_are_jumpers no)
		(fp_poly
			(pts
				(xy -0.4953 -0.2032) (xy 0.4953 -0.2032) (xy 0.4953 1.6002) (xy -0.4953 1.6002)
			)
			(stroke
				(width 0)
				(type default)
			)
			(fill no)
			(layer "F.CrtYd")
		)
		(fp_line
			(start -0.4953 -0.2032)
			(end 0.4953 -0.2032)
			(stroke
				(width 0.1)
				(type default)
			)
			(layer "F.Fab")
		)
		(fp_line
			(start -0.4953 1.6002)
			(end -0.4953 -0.2032)
			(stroke
				(width 0.1)
				(type default)
			)
			(layer "F.Fab")
		)
		(fp_line
			(start 0.4953 -0.2032)
			(end 0.4953 1.6002)
			(stroke
				(width 0.1)
				(type default)
			)
			(layer "F.Fab")
		)
		(fp_line
			(start 0.4953 1.6002)
			(end -0.4953 1.6002)
			(stroke
				(width 0.1)
				(type default)
			)
			(layer "F.Fab")
		)
		(pad "1" smd rect
			(at 0 0)
			(size 0.762 0.889)
			(layers "F.Cu" "F.Mask" "F.Paste")
			(net "PVPP_KLM")
		)
		(pad "2" smd rect
			(at 0 1.397)
			(size 0.762 0.889)
			(layers "F.Cu" "F.Mask" "F.Paste")
			(net "GND")
		)
		(zone
			(layer "F.Cu")
			(hatch none 0.5)
			(connect_pads
				(clearance 0)
			)
			(min_thickness 0.25)
			(keepout
				(tracks not_allowed)
				(vias allowed)
				(pads allowed)
				(copperpour not_allowed)
				(footprints allowed)
			)
			(placement
				(enabled no)
				(sheetname "")
			)
			(fill
				(thermal_gap 0.5)
				(thermal_bridge_width 0.5)
				(island_removal_mode 0)
			)
			(polygon
				(pts
					(xy 168.6687 -131.5847) (xy 169.4307 -131.5847) (xy 169.4307 -132.0927) (xy 168.6687 -132.0927)
				)
			)
		)
		(zone
			(layer "F.Cu")
			(hatch none 0.5)
			(connect_pads
				(clearance 0)
			)
			(min_thickness 0.25)
			(keepout
				(tracks allowed)
				(vias not_allowed)
				(pads allowed)
				(copperpour not_allowed)
				(footprints allowed)
			)
			(placement
				(enabled no)
				(sheetname "")
			)
			(fill
				(thermal_gap 0.5)
				(thermal_bridge_width 0.5)
				(island_removal_mode 0)
			)
			(polygon
				(pts
					(xy 169.4307 -131.5847) (xy 169.4307 -132.0927) (xy 168.6687 -132.0927) (xy 168.6687 -131.5847)
				)
			)
		)
	)
	(footprint ""
		(layer "F.Cu")
		(at 436.753 -125.603 180)
		(property "Reference" "Q8B1"
			(at 3.36804 -2.27203 0)
			(unlocked yes)
			(layer "F.SilkS")
			(effects
				(font
					(size 0.7874 0.5842)
					(thickness 0.1524)
				)
				(justify left)
			)
		)
		(property "Value" ""
			(at 0 0 180)
			(layer "F.Fab")
			(effects
				(font
					(size 1.27 1.27)
				)
			)
		)
		(duplicate_pad_numbers_are_jumpers no)
		(fp_line
			(start -0.245364 2.020062)
			(end 3.15468 2.020062)
			(stroke
				(width 0.1524)
				(type default)
			)
			(layer "F.SilkS")
		)
		(fp_line
			(start -0.245364 -1.379982)
			(end 3.15468 -1.379982)
			(stroke
				(width 0.1524)
				(type default)
			)
			(layer "F.SilkS")
		)
		(fp_circle
			(center -0.94996 -1.512316)
			(end -1.07696 -1.512316)
			(stroke
				(width 0.254)
				(type default)
			)
			(fill no)
			(layer "F.SilkS")
		)
		(fp_poly
			(pts
				(xy 0.890016 -0.82296) (xy 0.890016 1.46304) (xy 3.404616 1.46304) (xy 3.404616 1.13284) (xy 2.617216 1.13284)
				(xy 2.617216 0.811022) (xy 3.404616 0.811022) (xy 3.404616 0.480822) (xy 2.617216 0.480822) (xy 2.617216 0.159258)
				(xy 3.404616 0.159258) (xy 3.404616 -0.170942) (xy 2.617216 -0.170942) (xy 2.617216 -0.49276) (xy 3.404616 -0.49276)
				(xy 3.404616 -0.82296)
			)
			(stroke
				(width 0)
				(type default)
			)
			(fill yes)
			(layer "F.Paste")
		)
		(fp_poly
			(pts
				(xy -0.245364 -1.379982) (xy -0.245364 2.020062) (xy 3.15468 2.020062) (xy 3.15468 -1.379982)
			)
			(stroke
				(width 0)
				(type default)
			)
			(fill no)
			(layer "F.CrtYd")
		)
		(fp_line
			(start 3.15468 2.020062)
			(end -0.245364 2.020062)
			(stroke
				(width 0.1)
				(type default)
			)
			(layer "F.Fab")
		)
		(fp_line
			(start 3.15468 -1.379982)
			(end 3.15468 2.020062)
			(stroke
				(width 0.1)
				(type default)
			)
			(layer "F.Fab")
		)
		(fp_line
			(start -0.245364 2.020062)
			(end -0.245364 -1.379982)
			(stroke
				(width 0.1)
				(type default)
			)
			(layer "F.Fab")
		)
		(fp_line
			(start -0.245364 -1.379982)
			(end 3.15468 -1.379982)
			(stroke
				(width 0.1)
				(type default)
			)
			(layer "F.Fab")
		)
		(fp_circle
			(center -0.94996 -1.512316)
			(end -1.07696 -1.512316)
			(stroke
				(width 0.254)
				(type default)
			)
			(fill no)
			(layer "F.Fab")
		)
		(pad "1" smd custom
			(at 0 0 180)
			(size 0.24765 0.24765)
			(layers "F.Cu" "F.Mask" "F.Paste")
			(net "P5V")
			(options
				(clearance outline)
				(anchor circle)
			)
			(primitives
				(gr_poly
					(pts
						(xy 0.4953 0.8255) (xy 0.4953 -0.8255) (xy -0.4953 -0.8255) (xy -0.4953 -0.4953) (xy 0.0127 -0.4953)
						(xy 0.0127 -0.1651) (xy -0.4953 -0.1651) (xy -0.4953 0.1651) (xy 0.0127 0.1651) (xy 0.0127 0.4953)
						(xy -0.4953 0.4953) (xy -0.4953 0.8255)
					)
					(width 0)
					(fill yes)
				)
			)
		)
		(pad "4" smd rect
			(at 0 1.30048 180)
			(size 0.9906 0.3302)
			(layers "F.Cu" "F.Mask" "F.Paste")
			(net "P5V_SWITCH_G")
		)
		(pad "5" smd custom
			(at 2.147316 0.32004 180)
			(size 0.5715 0.5715)
			(layers "F.Cu" "F.Mask" "F.Paste")
			(net "P5V_STBY")
			(options
				(clearance outline)
				(anchor circle)
			)
			(primitives
				(gr_poly
					(pts
						(xy -1.2573 -1.143) (xy -1.2573 1.143) (xy 1.2573 1.143) (xy 1.2573 0.8128) (xy 0.4699 0.8128)
						(xy 0.4699 0.490982) (xy 1.2573 0.490982) (xy 1.2573 0.160782) (xy 0.4699 0.160782) (xy 0.4699 -0.160782)
						(xy 1.2573 -0.160782) (xy 1.2573 -0.490982) (xy 0.4699 -0.490982) (xy 0.4699 -0.8128) (xy 1.2573 -0.8128)
						(xy 1.2573 -1.143)
					)
					(width 0)
					(fill yes)
				)
			)
		)
	)
	(footprint ""
		(layer "F.Cu")
		(at 164.480494 -34.671)
		(property "Reference" "C4F2"
			(at 0 0 0)
			(layer "F.SilkS")
			(hide yes)
			(effects
				(font
					(size 1.27 1.27)
				)
			)
		)
		(property "Value" ""
			(at 0 0 0)
			(layer "F.Fab")
			(effects
				(font
					(size 1.27 1.27)
				)
			)
		)
		(duplicate_pad_numbers_are_jumpers no)
		(fp_rect
			(start -0.500126 1.598422)
			(end 0.500126 -0.201422)
			(stroke
				(width 0)
				(type default)
			)
			(fill no)
			(layer "F.CrtYd")
		)
		(fp_line
			(start -0.500126 -0.201422)
			(end 0.500126 -0.201422)
			(stroke
				(width 0.1)
				(type default)
			)
			(layer "F.Fab")
		)
		(fp_line
			(start -0.500126 1.598422)
			(end -0.500126 -0.201422)
			(stroke
				(width 0.1)
				(type default)
			)
			(layer "F.Fab")
		)
		(fp_line
			(start 0.500126 -0.201422)
			(end 0.500126 1.598422)
			(stroke
				(width 0.1)
				(type default)
			)
			(layer "F.Fab")
		)
		(fp_line
			(start 0.500126 1.598422)
			(end -0.500126 1.598422)
			(stroke
				(width 0.1)
				(type default)
			)
			(layer "F.Fab")
		)
		(pad "1" smd rect
			(at 0 0 270)
			(size 0.889 0.9906)
			(layers "F.Cu" "F.Mask" "F.Paste")
			(net "P1V8_MCP_CPU1")
		)
		(pad "2" smd rect
			(at 0 1.397 270)
			(size 0.889 0.9906)
			(layers "F.Cu" "F.Mask" "F.Paste")
			(net "GND")
		)
		(zone
			(layer "F.Cu")
			(hatch none 0.5)
			(connect_pads
				(clearance 0)
			)
			(min_thickness 0.25)
			(keepout
				(tracks not_allowed)
				(vias allowed)
				(pads allowed)
				(copperpour not_allowed)
				(footprints allowed)
			)
			(placement
				(enabled no)
				(sheetname "")
			)
			(fill
				(thermal_gap 0.5)
				(thermal_bridge_width 0.5)
				(island_removal_mode 0)
			)
			(polygon
				(pts
					(xy 163.985194 -33.7185) (xy 164.975794 -33.7185) (xy 164.975794 -34.2265) (xy 163.985194 -34.2265)
				)
			)
		)
		(zone
			(layer "F.Cu")
			(hatch none 0.5)
			(connect_pads
				(clearance 0)
			)
			(min_thickness 0.25)
			(keepout
				(tracks allowed)
				(vias not_allowed)
				(pads allowed)
				(copperpour not_allowed)
				(footprints allowed)
			)
			(placement
				(enabled no)
				(sheetname "")
			)
			(fill
				(thermal_gap 0.5)
				(thermal_bridge_width 0.5)
				(island_removal_mode 0)
			)
			(polygon
				(pts
					(xy 163.985194 -33.7185) (xy 164.975794 -33.7185) (xy 164.975794 -34.2265) (xy 163.985194 -34.2265)
				)
			)
		)
	)
	(footprint ""
		(layer "F.Cu")
		(at 111.000032 -12.954 90)
		(property "Reference" "C3G2"
			(at 1.848866 0.752348 90)
			(unlocked yes)
			(layer "F.SilkS")
			(effects
				(font
					(size 1.27 0.9652)
					(thickness 0.1524)
				)
			)
		)
		(property "Value" ""
			(at 0 0 90)
			(layer "F.Fab")
			(effects
				(font
					(size 1.27 1.27)
				)
			)
		)
		(duplicate_pad_numbers_are_jumpers no)
		(fp_rect
			(start -0.500126 1.598422)
			(end 0.500126 -0.201422)
			(stroke
				(width 0)
				(type default)
			)
			(fill no)
			(layer "F.CrtYd")
		)
		(fp_line
			(start 0.500126 -0.201422)
			(end 0.500126 1.598422)
			(stroke
				(width 0.1)
				(type default)
			)
			(layer "F.Fab")
		)
		(fp_line
			(start -0.500126 -0.201422)
			(end 0.500126 -0.201422)
			(stroke
				(width 0.1)
				(type default)
			)
			(layer "F.Fab")
		)
		(fp_line
			(start 0.500126 1.598422)
			(end -0.500126 1.598422)
			(stroke
				(width 0.1)
				(type default)
			)
			(layer "F.Fab")
		)
		(fp_line
			(start -0.500126 1.598422)
			(end -0.500126 -0.201422)
			(stroke
				(width 0.1)
				(type default)
			)
			(layer "F.Fab")
		)
		(pad "1" smd rect
			(at 0 0)
			(size 0.889 0.9906)
			(layers "F.Cu" "F.Mask" "F.Paste")
			(net "PVDDQ_GHJ")
		)
		(pad "2" smd rect
			(at 0 1.397)
			(size 0.889 0.9906)
			(layers "F.Cu" "F.Mask" "F.Paste")
			(net "GND")
		)
		(zone
			(layer "F.Cu")
			(hatch none 0.5)
			(connect_pads
				(clearance 0)
			)
			(min_thickness 0.25)
			(keepout
				(tracks not_allowed)
				(vias allowed)
				(pads allowed)
				(copperpour not_allowed)
				(footprints allowed)
			)
			(placement
				(enabled no)
				(sheetname "")
			)
			(fill
				(thermal_gap 0.5)
				(thermal_bridge_width 0.5)
				(island_removal_mode 0)
			)
			(polygon
				(pts
					(xy 111.952532 -12.4587) (xy 111.952532 -13.4493) (xy 111.444532 -13.4493) (xy 111.444532 -12.4587)
				)
			)
		)
		(zone
			(layer "F.Cu")
			(hatch none 0.5)
			(connect_pads
				(clearance 0)
			)
			(min_thickness 0.25)
			(keepout
				(tracks allowed)
				(vias not_allowed)
				(pads allowed)
				(copperpour not_allowed)
				(footprints allowed)
			)
			(placement
				(enabled no)
				(sheetname "")
			)
			(fill
				(thermal_gap 0.5)
				(thermal_bridge_width 0.5)
				(island_removal_mode 0)
			)
			(polygon
				(pts
					(xy 111.952532 -12.4587) (xy 111.952532 -13.4493) (xy 111.444532 -13.4493) (xy 111.444532 -12.4587)
				)
			)
		)
	)
)
